# TIMECARD (Time Appliance Project (Time Card)) — schematic netlist excerpt (pin names and nets, part order shuffled) for the footprints in the layout excerpt that follows; sources: Cadence DE-HDL packaged netlist, KiCad conversion of R4006-B0001-02_R01.brd

R148  RESISTOR  10KOHM 1%  pkg SMC_0402R_H016  page 16 : \1\ = XP3R3V_FPGA ; \2\ = R_PCA9546_I2C_SCL
R119  RESISTOR  330OHM 1%  pkg SMC_0402R_H016  page 26 : \1\ = UNNAMED_14_OPTICAL_I194_A ; \2\ = XP3R3V_AUX_PCIE

(kicad_pcb
	(version 20260206)
	(generator "pcbnew")
	(generator_version "10.0")
	(general
		(thickness 1.6)
		(legacy_teardrops no)
	)
	(paper "A4")
	(title_block
		(title "timecard-production-celestica-r4006 — R4006-B0001-02_R01.brd")
		(comment 1 "Time Appliance Project (Time Card) / footprints 896-897 of 1113")
	)
	(layers
		(0 "F.Cu" signal "TOP")
		(4 "In1.Cu" signal "L02_GND1")
		(6 "In2.Cu" signal "L03_SIG1")
		(8 "In3.Cu" signal "L04_GND2")
		(10 "In4.Cu" signal "L05_VCC1")
		(12 "In5.Cu" signal "L06_VCC2")
		(14 "In6.Cu" signal "L07_GND3")
		(16 "In7.Cu" signal "L08_SIG2")
		(18 "In8.Cu" signal "L09_GND4")
		(2 "B.Cu" signal "BOTTOM")
		(9 "F.Adhes" user "F.Adhesive")
		(11 "B.Adhes" user "B.Adhesive")
		(13 "F.Paste" user "Package Geometry/Pastemask Top")
		(15 "B.Paste" user "Package Geometry/Pastemask Bottom")
		(5 "F.SilkS" user "Ref Des/Silkscreen Top")
		(7 "B.SilkS" user "Ref Des/Silkscreen Bottom")
		(1 "F.Mask" user "Board Geometry/Soldermask Top")
		(3 "B.Mask" user "Board Geometry/Soldermask Bottom")
		(17 "Dwgs.User" user "User.Drawings")
		(19 "Cmts.User" user "User.Comments")
		(21 "Eco1.User" user "User.Eco1")
		(23 "Eco2.User" user "User.Eco2")
		(25 "Edge.Cuts" user "Board Geometry/Outline")
		(27 "Margin" user)
		(31 "F.CrtYd" user "Package Geometry/Place Bound Top")
		(29 "B.CrtYd" user "Package Geometry/Place Bound Bottom")
		(35 "F.Fab" user "Ref Des/Assembly Top")
		(33 "B.Fab" user "Ref Des/Assembly Bottom")
	)
	(footprint ""
		(layer "B.Cu")
		(at 153.035 -104.394 90)
		(property "Reference" "R119"
			(at -1.27 1.10363 270)
			(unlocked yes)
			(layer "B.SilkS")
			(effects
				(font
					(size 0.7874 0.5842)
					(thickness 0.1524)
				)
				(justify mirror)
			)
		)
		(property "Value" "VAL*"
			(at -0.02032 2.13233 90)
			(unlocked yes)
			(layer "B.Fab")
			(hide yes)
			(effects
				(font
					(size 0.7874 0.5842)
					(thickness 0.1524)
				)
				(justify mirror)
			)
		)
		(property "Tolerance" "TOL*"
			(at -0.044704 3.05435 90)
			(unlocked yes)
			(layer "Cmts.User")
			(hide yes)
			(effects
				(font
					(size 0.7874 0.5842)
					(thickness 0.1524)
				)
				(justify mirror)
			)
		)
		(property "User Part Number" "PARTNUM*"
			(at -0.02032 4.024884 90)
			(unlocked yes)
			(layer "Cmts.User")
			(hide yes)
			(effects
				(font
					(size 0.7874 0.5842)
					(thickness 0.1524)
				)
				(justify mirror)
			)
		)
		(property "Device Type" "RESISTOR-G155-13300-01,330OHM,A"
			(at -0.008382 1.210564 90)
			(unlocked yes)
			(layer "B.Fab")
			(hide yes)
			(effects
				(font
					(size 0.7874 0.5842)
					(thickness 0.1524)
				)
				(justify mirror)
			)
		)
		(duplicate_pad_numbers_are_jumpers no)
		(fp_line
			(start 1.143 -0.5588)
			(end 1.143 0.5588)
			(stroke
				(width 0.1)
				(type default)
			)
			(layer "B.SilkS")
		)
		(fp_line
			(start -1.143 -0.5588)
			(end 1.143 -0.5588)
			(stroke
				(width 0.1)
				(type default)
			)
			(layer "B.SilkS")
		)
		(fp_line
			(start 1.143 0.5588)
			(end -1.143 0.5588)
			(stroke
				(width 0.1)
				(type default)
			)
			(layer "B.SilkS")
		)
		(fp_line
			(start -1.143 0.5588)
			(end -1.143 -0.5588)
			(stroke
				(width 0.1)
				(type default)
			)
			(layer "B.SilkS")
		)
		(fp_poly
			(pts
				(xy 1.143 0.5588) (xy -1.143 0.5588) (xy -1.143 -0.5588) (xy 1.143 -0.5588)
			)
			(stroke
				(width 0)
				(type default)
			)
			(fill no)
			(layer "B.CrtYd")
		)
		(fp_line
			(start 0.508 -0.3048)
			(end 0.508 0.3048)
			(stroke
				(width 0.1)
				(type default)
			)
			(layer "B.Fab")
		)
		(fp_line
			(start -0.508 -0.3048)
			(end 0.508 -0.3048)
			(stroke
				(width 0.1)
				(type default)
			)
			(layer "B.Fab")
		)
		(fp_line
			(start 0.508 0.3048)
			(end -0.508 0.3048)
			(stroke
				(width 0.1)
				(type default)
			)
			(layer "B.Fab")
		)
		(fp_line
			(start -0.508 0.3048)
			(end -0.508 -0.3048)
			(stroke
				(width 0.1)
				(type default)
			)
			(layer "B.Fab")
		)
		(pad "1" smd rect
			(at 0.5334 0 270)
			(size 0.7112 0.6096)
			(layers "B.Cu" "B.Mask" "B.Paste")
			(net "UNNAMED_14_OPTICAL_I194_A")
		)
		(pad "2" smd rect
			(at -0.5334 0 270)
			(size 0.7112 0.6096)
			(layers "B.Cu" "B.Mask" "B.Paste")
			(net "XP3R3V_AUX_PCIE")
		)
		(zone
			(layer "B.Cu")
			(hatch none 0.5)
			(connect_pads
				(clearance 0)
			)
			(min_thickness 0.25)
			(keepout
				(tracks allowed)
				(vias not_allowed)
				(pads allowed)
				(copperpour not_allowed)
				(footprints allowed)
			)
			(placement
				(enabled no)
				(sheetname "")
			)
			(fill
				(thermal_gap 0.5)
				(thermal_bridge_width 0.5)
				(island_removal_mode 0)
			)
			(polygon
				(pts
					(xy 153.3398 -104.4702) (xy 152.7302 -104.4702) (xy 152.7302 -104.3178) (xy 153.3398 -104.3178)
				)
			)
		)
		(zone
			(layer "B.Cu")
			(hatch none 0.5)
			(connect_pads
				(clearance 0)
			)
			(min_thickness 0.25)
			(keepout
				(tracks not_allowed)
				(vias allowed)
				(pads allowed)
				(copperpour not_allowed)
				(footprints allowed)
			)
			(placement
				(enabled no)
				(sheetname "")
			)
			(fill
				(thermal_gap 0.5)
				(thermal_bridge_width 0.5)
				(island_removal_mode 0)
			)
			(polygon
				(pts
					(xy 153.3398 -104.4702) (xy 152.7302 -104.4702) (xy 152.7302 -104.3178) (xy 153.3398 -104.3178)
				)
			)
		)
	)
	(footprint ""
		(layer "B.Cu")
		(at 21.0566 -39.3446)
		(property "Reference" "R148"
			(at -0.3556 4.71297 0)
			(unlocked yes)
			(layer "B.SilkS")
			(effects
				(font
					(size 0.7874 0.5842)
					(thickness 0.1524)
				)
				(justify mirror)
			)
		)
		(property "Value" "VAL*"
			(at -0.02032 2.13233 0)
			(unlocked yes)
			(layer "B.Fab")
			(hide yes)
			(effects
				(font
					(size 0.7874 0.5842)
					(thickness 0.1524)
				)
				(justify mirror)
			)
		)
		(property "Device Type" "RESISTOR-G155-11002-01,10KOHM,A"
			(at -0.008382 1.210564 0)
			(unlocked yes)
			(layer "B.Fab")
			(hide yes)
			(effects
				(font
					(size 0.7874 0.5842)
					(thickness 0.1524)
				)
				(justify mirror)
			)
		)
		(property "User Part Number" "PARTNUM*"
			(at -0.02032 4.024884 0)
			(unlocked yes)
			(layer "Cmts.User")
			(hide yes)
			(effects
				(font
					(size 0.7874 0.5842)
					(thickness 0.1524)
				)
				(justify mirror)
			)
		)
		(property "Tolerance" "TOL*"
			(at -0.044704 3.05435 0)
			(unlocked yes)
			(layer "Cmts.User")
			(hide yes)
			(effects
				(font
					(size 0.7874 0.5842)
					(thickness 0.1524)
				)
				(justify mirror)
			)
		)
		(duplicate_pad_numbers_are_jumpers no)
		(fp_line
			(start -1.143 -0.5588)
			(end 1.143 -0.5588)
			(stroke
				(width 0.1)
				(type default)
			)
			(layer "B.SilkS")
		)
		(fp_line
			(start -1.143 0.5588)
			(end -1.143 -0.5588)
			(stroke
				(width 0.1)
				(type default)
			)
			(layer "B.SilkS")
		)
		(fp_line
			(start 1.143 -0.5588)
			(end 1.143 0.5588)
			(stroke
				(width 0.1)
				(type default)
			)
			(layer "B.SilkS")
		)
		(fp_line
			(start 1.143 0.5588)
			(end -1.143 0.5588)
			(stroke
				(width 0.1)
				(type default)
			)
			(layer "B.SilkS")
		)
		(fp_rect
			(start 1.143 0.5588)
			(end -1.143 -0.5588)
			(stroke
				(width 0)
				(type default)
			)
			(fill no)
			(layer "B.CrtYd")
		)
		(fp_line
			(start -0.508 -0.3048)
			(end 0.508 -0.3048)
			(stroke
				(width 0.1)
				(type default)
			)
			(layer "B.Fab")
		)
		(fp_line
			(start -0.508 0.3048)
			(end -0.508 -0.3048)
			(stroke
				(width 0.1)
				(type default)
			)
			(layer "B.Fab")
		)
		(fp_line
			(start 0.508 -0.3048)
			(end 0.508 0.3048)
			(stroke
				(width 0.1)
				(type default)
			)
			(layer "B.Fab")
		)
		(fp_line
			(start 0.508 0.3048)
			(end -0.508 0.3048)
			(stroke
				(width 0.1)
				(type default)
			)
			(layer "B.Fab")
		)
		(pad "1" smd rect
			(at 0.5334 0 180)
			(size 0.7112 0.6096)
			(layers "B.Cu" "B.Mask" "B.Paste")
			(net "XP3R3V_FPGA")
		)
		(pad "2" smd rect
			(at -0.5334 0 180)
			(size 0.7112 0.6096)
			(layers "B.Cu" "B.Mask" "B.Paste")
			(net "R_PCA9546_I2C_SCL")
		)
		(zone
			(layer "B.Cu")
			(hatch none 0.5)
			(connect_pads
				(clearance 0)
			)
			(min_thickness 0.25)
			(keepout
				(tracks allowed)
				(vias not_allowed)
				(pads allowed)
				(copperpour not_allowed)
				(footprints allowed)
			)
			(placement
				(enabled no)
				(sheetname "")
			)
			(fill
				(thermal_gap 0.5)
				(thermal_bridge_width 0.5)
				(island_removal_mode 0)
			)
			(polygon
				(pts
					(xy 21.1328 -39.0398) (xy 21.1328 -39.6494) (xy 20.9804 -39.6494) (xy 20.9804 -39.0398)
				)
			)
		)
	)
)
